# S9S_MB_2U (Grand Teton) — schematic netlist excerpt (pin names and nets, part order shuffled) for the footprints in the layout excerpt that follows; sources: Cadence DE-HDL packaged netlist, KiCad conversion of 03242023_DA0F0TMBIJ0_F0T_Motherboard_J_brd_V01_OCP.brd

PU14  RAA229126GNPHA0  RAA229126GNP#HA0 IC  pkg QFN48_THXT  page 266
  PWM0  = PVCCFA_EHV_FIVRA_CPU0_PWM1
  PWM1  = PVCCFA_EHV_FIVRA_CPU0_PWM2
  PWM2  = PVCCFA_EHV_FIVRA_CPU0_PWM3
  PWM3  = PVCCFA_EHV_FIVRA_CPU0_PWM4
  PWM4  = PVCCIN_CPU0_PWM8
  PWM5  = PVCCIN_CPU0_PWM7
  PWM6  = PVCCIN_CPU0_PWM6
  PWM7  = PVCCIN_CPU0_PWM5
  PWM8  = PVCCIN_CPU0_PWM4
  PWM9  = PVCCIN_CPU0_PWM3
  PWM10  = PVCCIN_CPU0_PWM2
  PWM11  = PVCCIN_CPU0_PWM1
  PMSDA  = SMB_DIO_PVCCIN_CPU0
  PMSCL  = SMB_CLK_PVCCIN_CPU0
  NPMALERT  = NC_PVCCIN_CPU0_SMB_ALERT
  PG0  = PWRGD_PVCCIN_CPU0_R
  EN0  = PVCCIN_CPU0_EN_R
  NVRHOT  = IRQ_PVCCIN_CPU0_VRHOT_N
  \npinalert||npsys_crit\  = PVCCIN_CPU0_PIN_ALERT
  PG1  = PWRGD_PVCCFA_EHV_FIVRA_CPU0_R
  SVCLK  = SVID_CLK_PVCCIN_CPU0_R
  SVDATA  = SVID_DIO_PVCCIN_CPU0_R
  NSVALERT  = SVID_ALERT_PVCCIN_CPU0_R
  EN1  = PVCCFA_EHV_FIVRA_CPU0_EN_R
  VSEN0  = SH_PVCCIN_CPU0_R
  RGND0  = VSENSE_PVCCIN_CPU0_DN
  CS11  = PVCCIN_CPU0_IMON1
  CS10  = PVCCIN_CPU0_IMON2
  CS9  = PVCCIN_CPU0_IMON3
  CS8  = PVCCIN_CPU0_IMON4
  CS7  = PVCCIN_CPU0_IMON5
  CS6  = PVCCIN_CPU0_IMON6
  CS5  = PVCCIN_CPU0_IMON7
  CS4  = PVCCIN_CPU0_IMON8
  CS3  = PVCCFA_EHV_FIVRA_CPU0_IMON4
  CS2  = PVCCFA_EHV_FIVRA_CPU0_IMON3
  CS1  = PVCCFA_EHV_FIVRA_CPU0_IMON2
  CS0  = PVCCFA_EHV_FIVRA_CPU0_IMON1
  RGND1  = VSENSE_PVCCFA_EHV_FIVRA_CPU0_DN
  VSEN1  = SH_PVCCFA_EHV_FIVRA_CPU0_R
  CFP  = PVCCIN_CPU0_VR_FAULT
  ADDR_CFG  = PVCCIN_CPU0_ADDR
  TEMP0  = PVCCIN_CPU0_ATSEN
  \temp1||isys\  = PVCCFA_EHV_FIVRA_CPU0_BTSEN
  \vmon||iinsen||vsys||isys\  = PVCCIN_CPU0_CSPIN
  \vinsen||vsys\  = PVCCIN_CPU0_VIN_CSNIN
  VCC  = PVCCIN_CPU0_VCC
  VCCS  = PVCCIN_CPU0_VREF
  TH_GND  = GND

(kicad_pcb
	(version 20260206)
	(generator "pcbnew")
	(generator_version "10.0")
	(general
		(thickness 1.6)
		(legacy_teardrops no)
	)
	(paper "A4")
	(title_block
		(title "03242023_DA0F0TMBIJ0_F0T_Motherboard_J_brd_V01_OCP.brd")
		(comment 1 "Grand Teton / footprint 2912 of 6105 (PU14), pads 1-42 of 49")
	)
	(layers
		(0 "F.Cu" signal "TOP")
		(4 "In1.Cu" signal "GND")
		(6 "In2.Cu" signal "IN1")
		(8 "In3.Cu" signal "GND1")
		(10 "In4.Cu" signal "IN2")
		(12 "In5.Cu" signal "GND2")
		(14 "In6.Cu" signal "IN3")
		(16 "In7.Cu" signal "GND3")
		(18 "In8.Cu" signal "VCC")
		(20 "In9.Cu" signal "VCC1")
		(22 "In10.Cu" signal "GND4")
		(24 "In11.Cu" signal "IN4")
		(26 "In12.Cu" signal "GND5")
		(28 "In13.Cu" signal "IN5")
		(30 "In14.Cu" signal "GND6")
		(32 "In15.Cu" signal "IN6")
		(34 "In16.Cu" signal "GND7")
		(2 "B.Cu" signal "BOTTOM")
		(9 "F.Adhes" user "F.Adhesive")
		(11 "B.Adhes" user "B.Adhesive")
		(13 "F.Paste" user "Package Geometry/Pastemask Top")
		(15 "B.Paste" user "Package Geometry/Pastemask Bottom")
		(5 "F.SilkS" user "Ref Des/Silkscreen Top")
		(7 "B.SilkS" user "Ref Des/Silkscreen Bottom")
		(1 "F.Mask" user "Board Geometry/Soldermask Top")
		(3 "B.Mask" user "Board Geometry/Soldermask Bottom")
		(17 "Dwgs.User" user "User.Drawings")
		(19 "Cmts.User" user "User.Comments")
		(21 "Eco1.User" user "User.Eco1")
		(23 "Eco2.User" user "User.Eco2")
		(25 "Edge.Cuts" user "Board Geometry/Outline")
		(27 "Margin" user)
		(31 "F.CrtYd" user "Package Geometry/Place Bound Top")
		(29 "B.CrtYd" user "Package Geometry/Place Bound Bottom")
		(35 "F.Fab" user "Ref Des/Assembly Top")
		(33 "B.Fab" user "Ref Des/Assembly Bottom")
	)
	(footprint ""
		(layer "F.Cu")
		(at 356.51821 -358.848406 -90)
		(property "Reference" "PU14"
			(at -7.271512 3.70967 0)
			(unlocked yes)
			(layer "F.SilkS")
			(effects
				(font
					(size 0.7874 0.5842)
					(thickness 0.1524)
				)
				(justify left)
			)
		)
		(property "Value" ""
			(at 0 0 270)
			(layer "F.Fab")
			(effects
				(font
					(size 1.27 1.27)
				)
			)
		)
		(duplicate_pad_numbers_are_jumpers no)
		(pad "1" smd rect
			(at -2.875026 -2.199894)
			(size 0.1778 0.6604)
			(layers "F.Cu" "F.Mask" "F.Paste")
			(net "PVCCFA_EHV_FIVRA_CPU0_PWM1")
		)
		(pad "2" smd rect
			(at -2.875026 -1.800098)
			(size 0.1778 0.6604)
			(layers "F.Cu" "F.Mask" "F.Paste")
			(net "PVCCFA_EHV_FIVRA_CPU0_PWM2")
		)
		(pad "3" smd rect
			(at -2.875026 -1.400048)
			(size 0.1778 0.6604)
			(layers "F.Cu" "F.Mask" "F.Paste")
			(net "PVCCFA_EHV_FIVRA_CPU0_PWM3")
		)
		(pad "4" smd rect
			(at -2.875026 -0.999998)
			(size 0.1778 0.6604)
			(layers "F.Cu" "F.Mask" "F.Paste")
			(net "PVCCFA_EHV_FIVRA_CPU0_PWM4")
		)
		(pad "5" smd rect
			(at -2.875026 -0.599948)
			(size 0.1778 0.6604)
			(layers "F.Cu" "F.Mask" "F.Paste")
			(net "PVCCIN_CPU0_PWM8")
		)
		(pad "6" smd rect
			(at -2.875026 -0.199898)
			(size 0.1778 0.6604)
			(layers "F.Cu" "F.Mask" "F.Paste")
			(net "PVCCIN_CPU0_PWM7")
		)
		(pad "7" smd rect
			(at -2.875026 0.199898)
			(size 0.1778 0.6604)
			(layers "F.Cu" "F.Mask" "F.Paste")
			(net "PVCCIN_CPU0_PWM6")
		)
		(pad "8" smd rect
			(at -2.875026 0.599948)
			(size 0.1778 0.6604)
			(layers "F.Cu" "F.Mask" "F.Paste")
			(net "PVCCIN_CPU0_PWM5")
		)
		(pad "9" smd rect
			(at -2.875026 0.999998)
			(size 0.1778 0.6604)
			(layers "F.Cu" "F.Mask" "F.Paste")
			(net "PVCCIN_CPU0_PWM4")
		)
		(pad "10" smd rect
			(at -2.875026 1.400048)
			(size 0.1778 0.6604)
			(layers "F.Cu" "F.Mask" "F.Paste")
			(net "PVCCIN_CPU0_PWM3")
		)
		(pad "11" smd rect
			(at -2.875026 1.800098)
			(size 0.1778 0.6604)
			(layers "F.Cu" "F.Mask" "F.Paste")
			(net "PVCCIN_CPU0_PWM2")
		)
		(pad "12" smd rect
			(at -2.875026 2.199894)
			(size 0.1778 0.6604)
			(layers "F.Cu" "F.Mask" "F.Paste")
			(net "PVCCIN_CPU0_PWM1")
		)
		(pad "13" smd rect
			(at -2.199894 2.875026 270)
			(size 0.1778 0.6604)
			(layers "F.Cu" "F.Mask" "F.Paste")
			(net "SMB_DIO_PVCCIN_CPU0")
		)
		(pad "14" smd rect
			(at -1.800098 2.875026 270)
			(size 0.1778 0.6604)
			(layers "F.Cu" "F.Mask" "F.Paste")
			(net "SMB_CLK_PVCCIN_CPU0")
		)
		(pad "15" smd rect
			(at -1.400048 2.875026 270)
			(size 0.1778 0.6604)
			(layers "F.Cu" "F.Mask" "F.Paste")
			(net "NC_PVCCIN_CPU0_SMB_ALERT")
		)
		(pad "16" smd rect
			(at -0.999998 2.875026 270)
			(size 0.1778 0.6604)
			(layers "F.Cu" "F.Mask" "F.Paste")
			(net "PWRGD_PVCCIN_CPU0_R")
		)
		(pad "17" smd rect
			(at -0.599948 2.875026 270)
			(size 0.1778 0.6604)
			(layers "F.Cu" "F.Mask" "F.Paste")
			(net "PVCCIN_CPU0_EN_R")
		)
		(pad "18" smd rect
			(at -0.199898 2.875026 270)
			(size 0.1778 0.6604)
			(layers "F.Cu" "F.Mask" "F.Paste")
			(net "IRQ_PVCCIN_CPU0_VRHOT_N")
		)
		(pad "19" smd rect
			(at 0.199898 2.875026 270)
			(size 0.1778 0.6604)
			(layers "F.Cu" "F.Mask" "F.Paste")
			(net "PVCCIN_CPU0_PIN_ALERT")
		)
		(pad "20" smd rect
			(at 0.599948 2.875026 270)
			(size 0.1778 0.6604)
			(layers "F.Cu" "F.Mask" "F.Paste")
			(net "PWRGD_PVCCFA_EHV_FIVRA_CPU0_R")
		)
		(pad "21" smd rect
			(at 0.999998 2.875026 270)
			(size 0.1778 0.6604)
			(layers "F.Cu" "F.Mask" "F.Paste")
			(net "SVID_CLK_PVCCIN_CPU0_R")
		)
		(pad "22" smd rect
			(at 1.400048 2.875026 270)
			(size 0.1778 0.6604)
			(layers "F.Cu" "F.Mask" "F.Paste")
			(net "SVID_DIO_PVCCIN_CPU0_R")
		)
		(pad "23" smd rect
			(at 1.800098 2.875026 270)
			(size 0.1778 0.6604)
			(layers "F.Cu" "F.Mask" "F.Paste")
			(net "SVID_ALERT_PVCCIN_CPU0_R")
		)
		(pad "24" smd rect
			(at 2.199894 2.875026 270)
			(size 0.1778 0.6604)
			(layers "F.Cu" "F.Mask" "F.Paste")
			(net "PVCCFA_EHV_FIVRA_CPU0_EN_R")
		)
		(pad "25" smd rect
			(at 2.875026 2.199894)
			(size 0.1778 0.6604)
			(layers "F.Cu" "F.Mask" "F.Paste")
			(net "SH_PVCCIN_CPU0_R")
		)
		(pad "26" smd rect
			(at 2.875026 1.800098)
			(size 0.1778 0.6604)
			(layers "F.Cu" "F.Mask" "F.Paste")
			(net "VSENSE_PVCCIN_CPU0_DN")
		)
		(pad "27" smd rect
			(at 2.875026 1.400048)
			(size 0.1778 0.6604)
			(layers "F.Cu" "F.Mask" "F.Paste")
			(net "PVCCIN_CPU0_IMON1")
		)
		(pad "28" smd rect
			(at 2.875026 0.999998)
			(size 0.1778 0.6604)
			(layers "F.Cu" "F.Mask" "F.Paste")
			(net "PVCCIN_CPU0_IMON2")
		)
		(pad "29" smd rect
			(at 2.875026 0.599948)
			(size 0.1778 0.6604)
			(layers "F.Cu" "F.Mask" "F.Paste")
			(net "PVCCIN_CPU0_IMON3")
		)
		(pad "30" smd rect
			(at 2.875026 0.199898)
			(size 0.1778 0.6604)
			(layers "F.Cu" "F.Mask" "F.Paste")
			(net "PVCCIN_CPU0_IMON4")
		)
		(pad "31" smd rect
			(at 2.875026 -0.199898)
			(size 0.1778 0.6604)
			(layers "F.Cu" "F.Mask" "F.Paste")
			(net "PVCCIN_CPU0_IMON5")
		)
		(pad "32" smd rect
			(at 2.875026 -0.599948)
			(size 0.1778 0.6604)
			(layers "F.Cu" "F.Mask" "F.Paste")
			(net "PVCCIN_CPU0_IMON6")
		)
		(pad "33" smd rect
			(at 2.875026 -0.999998)
			(size 0.1778 0.6604)
			(layers "F.Cu" "F.Mask" "F.Paste")
			(net "PVCCIN_CPU0_IMON7")
		)
		(pad "34" smd rect
			(at 2.875026 -1.400048)
			(size 0.1778 0.6604)
			(layers "F.Cu" "F.Mask" "F.Paste")
			(net "PVCCIN_CPU0_IMON8")
		)
		(pad "35" smd rect
			(at 2.875026 -1.800098)
			(size 0.1778 0.6604)
			(layers "F.Cu" "F.Mask" "F.Paste")
			(net "PVCCFA_EHV_FIVRA_CPU0_IMON4")
		)
		(pad "36" smd rect
			(at 2.875026 -2.199894)
			(size 0.1778 0.6604)
			(layers "F.Cu" "F.Mask" "F.Paste")
			(net "PVCCFA_EHV_FIVRA_CPU0_IMON3")
		)
		(pad "37" smd rect
			(at 2.199894 -2.875026 270)
			(size 0.1778 0.6604)
			(layers "F.Cu" "F.Mask" "F.Paste")
			(net "PVCCFA_EHV_FIVRA_CPU0_IMON2")
		)
		(pad "38" smd rect
			(at 1.800098 -2.875026 270)
			(size 0.1778 0.6604)
			(layers "F.Cu" "F.Mask" "F.Paste")
			(net "PVCCFA_EHV_FIVRA_CPU0_IMON1")
		)
		(pad "39" smd rect
			(at 1.400048 -2.875026 270)
			(size 0.1778 0.6604)
			(layers "F.Cu" "F.Mask" "F.Paste")
			(net "VSENSE_PVCCFA_EHV_FIVRA_CPU0_DN")
		)
		(pad "40" smd rect
			(at 0.999998 -2.875026 270)
			(size 0.1778 0.6604)
			(layers "F.Cu" "F.Mask" "F.Paste")
			(net "SH_PVCCFA_EHV_FIVRA_CPU0_R")
		)
		(pad "41" smd rect
			(at 0.599948 -2.875026 270)
			(size 0.1778 0.6604)
			(layers "F.Cu" "F.Mask" "F.Paste")
			(net "PVCCIN_CPU0_VR_FAULT")
		)
		(pad "42" smd rect
			(at 0.199898 -2.875026 270)
			(size 0.1778 0.6604)
			(layers "F.Cu" "F.Mask" "F.Paste")
			(net "PVCCIN_CPU0_ADDR")
		)
	)
)
